(kicad_pcb
	(version 20260206)
	(generator "pcbnew")
	(generator_version "10.0")
	(general
		(thickness 1.6)
		(legacy_teardrops no)
	)
	(paper "A4")
	(title_block
		(title "v1-chassis-manager — T6M_CM_d_v01_1031_1645.brd")
		(comment 1 "Open CloudServer (Microsoft) / footprints 2033-2042 of 2512")
	)
	(layers
		(0 "F.Cu" signal "TOP")
		(4 "In1.Cu" signal "GND1")
		(6 "In2.Cu" signal "IN1")
		(8 "In3.Cu" signal "VCC1")
		(10 "In4.Cu" signal "VCC2")
		(12 "In5.Cu" signal "GND2")
		(14 "In6.Cu" signal "IN2")
		(16 "In7.Cu" signal "IN3")
		(18 "In8.Cu" signal "GND3")
		(2 "B.Cu" signal "BOTTOM")
		(9 "F.Adhes" user "F.Adhesive")
		(11 "B.Adhes" user "B.Adhesive")
		(13 "F.Paste" user "Package Geometry/Pastemask Top")
		(15 "B.Paste" user "Package Geometry/Pastemask Bottom")
		(5 "F.SilkS" user "Ref Des/Silkscreen Top")
		(7 "B.SilkS" user "Ref Des/Silkscreen Bottom")
		(1 "F.Mask" user "Board Geometry/Soldermask Top")
		(3 "B.Mask" user "Board Geometry/Soldermask Bottom")
		(17 "Dwgs.User" user "User.Drawings")
		(19 "Cmts.User" user "User.Comments")
		(21 "Eco1.User" user "User.Eco1")
		(23 "Eco2.User" user "User.Eco2")
		(25 "Edge.Cuts" user "Board Geometry/Outline")
		(27 "Margin" user)
		(31 "F.CrtYd" user "Package Geometry/Place Bound Top")
		(29 "B.CrtYd" user "Package Geometry/Place Bound Bottom")
		(35 "F.Fab" user "Ref Des/Assembly Top")
		(33 "B.Fab" user "Ref Des/Assembly Bottom")
	)
	(footprint ""
		(layer "B.Cu")
		(at 69.335142 -137.52322 180)
		(property "Reference" "C252"
			(at 36.007802 -52.728622 0)
			(unlocked yes)
			(layer "B.SilkS")
			(effects
				(font
					(size 0.7874 0.5842)
					(thickness 0.1524)
				)
				(justify left mirror)
			)
		)
		(property "Value" ""
			(at 0 0 0)
			(layer "B.Fab")
			(effects
				(font
					(size 1.27 1.27)
				)
				(justify mirror)
			)
		)
		(duplicate_pad_numbers_are_jumpers no)
		(fp_line
			(start 0.7874 0.4064)
			(end 0.7874 -0.4064)
			(stroke
				(width 0.1524)
				(type default)
			)
			(layer "B.SilkS")
		)
		(fp_line
			(start 0.7874 -0.4064)
			(end -0.7874 -0.4064)
			(stroke
				(width 0.1524)
				(type default)
			)
			(layer "B.SilkS")
		)
		(fp_line
			(start 0 0.381)
			(end 0 -0.381)
			(stroke
				(width 0.1524)
				(type default)
			)
			(layer "B.SilkS")
		)
		(fp_line
			(start -0.7874 0.4064)
			(end 0.7874 0.4064)
			(stroke
				(width 0.1524)
				(type default)
			)
			(layer "B.SilkS")
		)
		(fp_line
			(start -0.7874 -0.4064)
			(end -0.7874 0.4064)
			(stroke
				(width 0.1524)
				(type default)
			)
			(layer "B.SilkS")
		)
		(fp_poly
			(pts
				(xy 0.5334 0.254) (xy 0.635 0.254) (xy 0.635 0.2286) (xy 0.635 -0.254) (xy 0.5334 -0.254) (xy 0.5334 -0.2794)
				(xy -0.5334 -0.2794) (xy -0.5334 -0.254) (xy -0.635 -0.254) (xy -0.635 0.254) (xy -0.5334 0.254)
				(xy -0.5334 0.2794) (xy 0.508 0.2794) (xy 0.5334 0.2794)
			)
			(stroke
				(width 0)
				(type default)
			)
			(fill no)
			(layer "B.CrtYd")
		)
		(pad "1" smd rect
			(at -0.40005 0)
			(size 0.4572 0.508)
			(layers "B.Cu" "B.Mask" "B.Paste")
			(net "P3V3_NODE1")
		)
		(pad "2" smd rect
			(at 0.40005 0)
			(size 0.4572 0.508)
			(layers "B.Cu" "B.Mask" "B.Paste")
			(net "GND")
		)
	)
	(footprint ""
		(layer "B.Cu")
		(at 130.8862 -46.3804)
		(property "Reference" "R1325"
			(at -1.3716 -0.40513 0)
			(unlocked yes)
			(layer "B.SilkS")
			(effects
				(font
					(size 0.7874 0.5842)
					(thickness 0.1524)
				)
				(justify left mirror)
			)
		)
		(property "Value" ""
			(at 0 0 0)
			(layer "B.Fab")
			(effects
				(font
					(size 1.27 1.27)
				)
				(justify mirror)
			)
		)
		(duplicate_pad_numbers_are_jumpers no)
		(fp_line
			(start -0.7874 -0.4064)
			(end -0.7874 0.4064)
			(stroke
				(width 0.1524)
				(type default)
			)
			(layer "B.SilkS")
		)
		(fp_line
			(start -0.7874 0.4064)
			(end 0.7874 0.4064)
			(stroke
				(width 0.1524)
				(type default)
			)
			(layer "B.SilkS")
		)
		(fp_line
			(start 0.7874 -0.4064)
			(end -0.7874 -0.4064)
			(stroke
				(width 0.1524)
				(type default)
			)
			(layer "B.SilkS")
		)
		(fp_line
			(start 0.7874 0.4064)
			(end 0.7874 -0.4064)
			(stroke
				(width 0.1524)
				(type default)
			)
			(layer "B.SilkS")
		)
		(fp_poly
			(pts
				(xy 0.508 0.2794) (xy 0.508 0.2286) (xy 0.635 0.2286) (xy 0.635 -0.254) (xy 0.5334 -0.254) (xy 0.5334 -0.2794)
				(xy -0.5334 -0.2794) (xy -0.5334 -0.254) (xy -0.635 -0.254) (xy -0.635 0.254) (xy -0.5334 0.254)
				(xy -0.5334 0.2794)
			)
			(stroke
				(width 0)
				(type default)
			)
			(fill no)
			(layer "B.CrtYd")
		)
		(pad "1" smd rect
			(at -0.40005 0 180)
			(size 0.4572 0.508)
			(layers "B.Cu" "B.Mask" "B.Paste")
			(net "P5V_NODE1")
		)
		(pad "2" smd rect
			(at 0.40005 0 180)
			(size 0.4572 0.508)
			(layers "B.Cu" "B.Mask" "B.Paste")
			(net "UART_CTS_P4_N")
		)
	)
	(footprint ""
		(layer "B.Cu")
		(at 144.909032 -38.710616)
		(property "Reference" "R1195"
			(at 1.24714 17.425924 0)
			(unlocked yes)
			(layer "B.SilkS")
			(effects
				(font
					(size 0.7874 0.5842)
					(thickness 0.1524)
				)
				(justify left mirror)
			)
		)
		(property "Value" ""
			(at 0 0 0)
			(layer "B.Fab")
			(effects
				(font
					(size 1.27 1.27)
				)
				(justify mirror)
			)
		)
		(duplicate_pad_numbers_are_jumpers no)
		(fp_line
			(start -0.7874 -0.4064)
			(end -0.7874 0.4064)
			(stroke
				(width 0.1524)
				(type default)
			)
			(layer "B.SilkS")
		)
		(fp_line
			(start -0.7874 0.4064)
			(end 0.7874 0.4064)
			(stroke
				(width 0.1524)
				(type default)
			)
			(layer "B.SilkS")
		)
		(fp_line
			(start 0.7874 -0.4064)
			(end -0.7874 -0.4064)
			(stroke
				(width 0.1524)
				(type default)
			)
			(layer "B.SilkS")
		)
		(fp_line
			(start 0.7874 0.4064)
			(end 0.7874 -0.4064)
			(stroke
				(width 0.1524)
				(type default)
			)
			(layer "B.SilkS")
		)
		(fp_poly
			(pts
				(xy 0.508 0.2794) (xy 0.508 0.2286) (xy 0.635 0.2286) (xy 0.635 -0.254) (xy 0.5334 -0.254) (xy 0.5334 -0.2794)
				(xy -0.5334 -0.2794) (xy -0.5334 -0.254) (xy -0.635 -0.254) (xy -0.635 0.254) (xy -0.5334 0.254)
				(xy -0.5334 0.2794)
			)
			(stroke
				(width 0)
				(type default)
			)
			(fill no)
			(layer "B.CrtYd")
		)
		(pad "1" smd rect
			(at -0.40005 0 180)
			(size 0.4572 0.508)
			(layers "B.Cu" "B.Mask" "B.Paste")
			(net "CPLD_WDT3_R")
		)
		(pad "2" smd rect
			(at 0.40005 0 180)
			(size 0.4572 0.508)
			(layers "B.Cu" "B.Mask" "B.Paste")
			(net "P3V3_NODE1")
		)
	)
	(footprint ""
		(layer "B.Cu")
		(at 88.840818 -80.83042)
		(property "Reference" "R119"
			(at -2.168398 9.526524 0)
			(unlocked yes)
			(layer "B.SilkS")
			(effects
				(font
					(size 0.7874 0.5842)
					(thickness 0.1524)
				)
				(justify left mirror)
			)
		)
		(property "Value" ""
			(at 0 0 0)
			(layer "B.Fab")
			(effects
				(font
					(size 1.27 1.27)
				)
				(justify mirror)
			)
		)
		(duplicate_pad_numbers_are_jumpers no)
		(fp_line
			(start -0.7874 -0.4064)
			(end -0.7874 0.4064)
			(stroke
				(width 0.1524)
				(type default)
			)
			(layer "B.SilkS")
		)
		(fp_line
			(start -0.7874 0.4064)
			(end 0.7874 0.4064)
			(stroke
				(width 0.1524)
				(type default)
			)
			(layer "B.SilkS")
		)
		(fp_line
			(start 0.7874 -0.4064)
			(end -0.7874 -0.4064)
			(stroke
				(width 0.1524)
				(type default)
			)
			(layer "B.SilkS")
		)
		(fp_line
			(start 0.7874 0.4064)
			(end 0.7874 -0.4064)
			(stroke
				(width 0.1524)
				(type default)
			)
			(layer "B.SilkS")
		)
		(fp_poly
			(pts
				(xy 0.508 0.2794) (xy 0.508 0.2286) (xy 0.635 0.2286) (xy 0.635 -0.254) (xy 0.5334 -0.254) (xy 0.5334 -0.2794)
				(xy -0.5334 -0.2794) (xy -0.5334 -0.254) (xy -0.635 -0.254) (xy -0.635 0.254) (xy -0.5334 0.254)
				(xy -0.5334 0.2794)
			)
			(stroke
				(width 0)
				(type default)
			)
			(fill no)
			(layer "B.CrtYd")
		)
		(pad "1" smd rect
			(at -0.40005 0 180)
			(size 0.4572 0.508)
			(layers "B.Cu" "B.Mask" "B.Paste")
			(net "SVID_CPU_NODE1_PVCCP_ALERT_L")
		)
		(pad "2" smd rect
			(at 0.40005 0 180)
			(size 0.4572 0.508)
			(layers "B.Cu" "B.Mask" "B.Paste")
			(net "P1V05_NODE1")
		)
	)
	(footprint ""
		(layer "B.Cu")
		(at 13.043916 -124.093478 180)
		(property "Reference" "PC57"
			(at 2.429764 0.090424 0)
			(unlocked yes)
			(layer "B.SilkS")
			(effects
				(font
					(size 0.7874 0.5842)
					(thickness 0.1524)
				)
				(justify left mirror)
			)
		)
		(property "Value" ""
			(at 0 0 0)
			(layer "B.Fab")
			(effects
				(font
					(size 1.27 1.27)
				)
				(justify mirror)
			)
		)
		(duplicate_pad_numbers_are_jumpers no)
		(fp_line
			(start 2.2098 0.9398)
			(end 2.2098 -0.9398)
			(stroke
				(width 0.1524)
				(type default)
			)
			(layer "B.SilkS")
		)
		(fp_line
			(start 2.2098 -0.9398)
			(end -2.2098 -0.9398)
			(stroke
				(width 0.1524)
				(type default)
			)
			(layer "B.SilkS")
		)
		(fp_line
			(start 0 -0.9398)
			(end 0 0.9398)
			(stroke
				(width 0.1524)
				(type default)
			)
			(layer "B.SilkS")
		)
		(fp_line
			(start -2.2098 0.9398)
			(end 2.2098 0.9398)
			(stroke
				(width 0.1524)
				(type default)
			)
			(layer "B.SilkS")
		)
		(fp_line
			(start -2.2098 -0.9398)
			(end -2.2098 0.9398)
			(stroke
				(width 0.1524)
				(type default)
			)
			(layer "B.SilkS")
		)
		(fp_poly
			(pts
				(xy 1.6764 0.889) (xy 1.6764 0.7874) (xy 2.0574 0.7874) (xy 2.0574 -0.7874) (xy 1.6764 -0.7874)
				(xy 1.6764 -0.9398) (xy -1.6764 -0.9398) (xy -1.6764 -0.7874) (xy -2.0574 -0.7874) (xy -2.0574 0.7874)
				(xy -1.6764 0.7874) (xy -1.6764 0.9398) (xy 1.6764 0.9398)
			)
			(stroke
				(width 0)
				(type default)
			)
			(fill no)
			(layer "B.CrtYd")
		)
		(fp_line
			(start 1.700022 0.899922)
			(end 1.700022 -0.899922)
			(stroke
				(width 0.1)
				(type default)
			)
			(layer "B.Fab")
		)
		(fp_line
			(start 1.700022 -0.899922)
			(end -1.700022 -0.899922)
			(stroke
				(width 0.1)
				(type default)
			)
			(layer "B.Fab")
		)
		(fp_line
			(start -1.700022 0.899922)
			(end 1.700022 0.899922)
			(stroke
				(width 0.1)
				(type default)
			)
			(layer "B.Fab")
		)
		(fp_line
			(start -1.700022 -0.899922)
			(end -1.700022 0.899922)
			(stroke
				(width 0.1)
				(type default)
			)
			(layer "B.Fab")
		)
		(pad "1" smd rect
			(at -1.4732 0)
			(size 1.1684 1.5748)
			(layers "B.Cu" "B.Mask" "B.Paste")
			(net "SW_P1V05_NODE1_VIN_FLT")
		)
		(pad "2" smd rect
			(at 1.4732 0)
			(size 1.1684 1.5748)
			(layers "B.Cu" "B.Mask" "B.Paste")
			(net "GND")
		)
	)
	(footprint ""
		(layer "B.Cu")
		(at 180.16093 -117.48262)
		(property "Reference" "C783"
			(at 2.884678 -0.19685 0)
			(unlocked yes)
			(layer "B.SilkS")
			(effects
				(font
					(size 0.7874 0.5842)
					(thickness 0.1524)
				)
				(justify mirror)
			)
		)
		(property "Value" ""
			(at 0 0 0)
			(layer "B.Fab")
			(effects
				(font
					(size 1.27 1.27)
				)
				(justify mirror)
			)
		)
		(duplicate_pad_numbers_are_jumpers no)
		(fp_line
			(start -1.2954 -0.5842)
			(end -1.2954 0.5842)
			(stroke
				(width 0.1524)
				(type default)
			)
			(layer "B.SilkS")
		)
		(fp_line
			(start -1.2954 0.5842)
			(end 1.2954 0.5842)
			(stroke
				(width 0.1524)
				(type default)
			)
			(layer "B.SilkS")
		)
		(fp_line
			(start 0 -0.5842)
			(end 0 0.5842)
			(stroke
				(width 0.1524)
				(type default)
			)
			(layer "B.SilkS")
		)
		(fp_line
			(start 1.2954 -0.5842)
			(end -1.2954 -0.5842)
			(stroke
				(width 0.1524)
				(type default)
			)
			(layer "B.SilkS")
		)
		(fp_line
			(start 1.2954 0.5842)
			(end 1.2954 -0.5842)
			(stroke
				(width 0.1524)
				(type default)
			)
			(layer "B.SilkS")
		)
		(fp_poly
			(pts
				(xy -0.8636 -0.4572) (xy -0.8636 -0.3556) (xy -1.143 -0.3556) (xy -1.143 0.3556) (xy -0.8636 0.3556)
				(xy -0.8636 0.4572) (xy 0.8636 0.4572) (xy 0.8636 0.3556) (xy 1.143 0.3556) (xy 1.143 -0.3556) (xy 0.8636 -0.3556)
				(xy 0.8636 -0.4572)
			)
			(stroke
				(width 0)
				(type default)
			)
			(fill no)
			(layer "B.CrtYd")
		)
		(fp_line
			(start -0.884936 -0.504952)
			(end -0.884936 0.504952)
			(stroke
				(width 0.1)
				(type default)
			)
			(layer "B.Fab")
		)
		(fp_line
			(start -0.884936 0.504952)
			(end 0.884936 0.504952)
			(stroke
				(width 0.1)
				(type default)
			)
			(layer "B.Fab")
		)
		(fp_line
			(start 0.884936 -0.504952)
			(end -0.884936 -0.504952)
			(stroke
				(width 0.1)
				(type default)
			)
			(layer "B.Fab")
		)
		(fp_line
			(start 0.884936 0.504952)
			(end 0.884936 -0.504952)
			(stroke
				(width 0.1)
				(type default)
			)
			(layer "B.Fab")
		)
		(pad "1" smd rect
			(at -0.7366 0 90)
			(size 0.7112 0.8128)
			(layers "B.Cu" "B.Mask" "B.Paste")
			(net "P3V3_STB_NODE1")
		)
		(pad "2" smd rect
			(at 0.7366 0 90)
			(size 0.7112 0.8128)
			(layers "B.Cu" "B.Mask" "B.Paste")
			(net "GND")
		)
	)
	(footprint ""
		(layer "B.Cu")
		(at 152.588214 -64.971422 90)
		(property "Reference" "C345"
			(at -2.01422 5.912866 270)
			(unlocked yes)
			(layer "B.SilkS")
			(effects
				(font
					(size 0.7874 0.5842)
					(thickness 0.1524)
				)
				(justify left mirror)
			)
		)
		(property "Value" ""
			(at 0 0 90)
			(layer "B.Fab")
			(effects
				(font
					(size 1.27 1.27)
				)
				(justify mirror)
			)
		)
		(duplicate_pad_numbers_are_jumpers no)
		(fp_line
			(start 0.7874 -0.4064)
			(end -0.7874 -0.4064)
			(stroke
				(width 0.1524)
				(type default)
			)
			(layer "B.SilkS")
		)
		(fp_line
			(start -0.7874 -0.4064)
			(end -0.7874 0.4064)
			(stroke
				(width 0.1524)
				(type default)
			)
			(layer "B.SilkS")
		)
		(fp_line
			(start 0 0.381)
			(end 0 -0.381)
			(stroke
				(width 0.1524)
				(type default)
			)
			(layer "B.SilkS")
		)
		(fp_line
			(start 0.7874 0.4064)
			(end 0.7874 -0.4064)
			(stroke
				(width 0.1524)
				(type default)
			)
			(layer "B.SilkS")
		)
		(fp_line
			(start -0.7874 0.4064)
			(end 0.7874 0.4064)
			(stroke
				(width 0.1524)
				(type default)
			)
			(layer "B.SilkS")
		)
		(fp_poly
			(pts
				(xy 0.5334 0.254) (xy 0.635 0.254) (xy 0.635 0.2286) (xy 0.635 -0.254) (xy 0.5334 -0.254) (xy 0.5334 -0.2794)
				(xy -0.5334 -0.2794) (xy -0.5334 -0.254) (xy -0.635 -0.254) (xy -0.635 0.254) (xy -0.5334 0.254)
				(xy -0.5334 0.2794) (xy 0.508 0.2794) (xy 0.5334 0.2794)
			)
			(stroke
				(width 0)
				(type default)
			)
			(fill no)
			(layer "B.CrtYd")
		)
		(pad "1" smd rect
			(at -0.40005 0 270)
			(size 0.4572 0.508)
			(layers "B.Cu" "B.Mask" "B.Paste")
			(net "GND")
		)
		(pad "2" smd rect
			(at 0.40005 0 270)
			(size 0.4572 0.508)
			(layers "B.Cu" "B.Mask" "B.Paste")
			(net "P1V8_SATA_VAA2_0_NODE1")
		)
	)
	(footprint ""
		(layer "B.Cu")
		(at 123.70816 -174.410624)
		(property "Reference" "R727"
			(at -28.598876 31.521146 0)
			(unlocked yes)
			(layer "B.SilkS")
			(effects
				(font
					(size 0.7874 0.5842)
					(thickness 0.1524)
				)
				(justify left mirror)
			)
		)
		(property "Value" ""
			(at 0 0 0)
			(layer "B.Fab")
			(effects
				(font
					(size 1.27 1.27)
				)
				(justify mirror)
			)
		)
		(duplicate_pad_numbers_are_jumpers no)
		(fp_line
			(start -0.7874 -0.4064)
			(end -0.7874 0.4064)
			(stroke
				(width 0.1524)
				(type default)
			)
			(layer "B.SilkS")
		)
		(fp_line
			(start -0.7874 0.4064)
			(end 0.7874 0.4064)
			(stroke
				(width 0.1524)
				(type default)
			)
			(layer "B.SilkS")
		)
		(fp_line
			(start 0.7874 -0.4064)
			(end -0.7874 -0.4064)
			(stroke
				(width 0.1524)
				(type default)
			)
			(layer "B.SilkS")
		)
		(fp_line
			(start 0.7874 0.4064)
			(end 0.7874 -0.4064)
			(stroke
				(width 0.1524)
				(type default)
			)
			(layer "B.SilkS")
		)
		(fp_poly
			(pts
				(xy 0.508 0.2794) (xy 0.508 0.2286) (xy 0.635 0.2286) (xy 0.635 -0.254) (xy 0.5334 -0.254) (xy 0.5334 -0.2794)
				(xy -0.5334 -0.2794) (xy -0.5334 -0.254) (xy -0.635 -0.254) (xy -0.635 0.254) (xy -0.5334 0.254)
				(xy -0.5334 0.2794)
			)
			(stroke
				(width 0)
				(type default)
			)
			(fill no)
			(layer "B.CrtYd")
		)
		(pad "1" smd rect
			(at -0.40005 0 180)
			(size 0.4572 0.508)
			(layers "B.Cu" "B.Mask" "B.Paste")
			(net "T8_NODE4_EN")
		)
		(pad "2" smd rect
			(at 0.40005 0 180)
			(size 0.4572 0.508)
			(layers "B.Cu" "B.Mask" "B.Paste")
			(net "P5V_NODE1")
		)
	)
	(footprint ""
		(layer "B.Cu")
		(at 53.193442 -29.199078)
		(property "Reference" "R210"
			(at 4.075938 -0.073152 0)
			(unlocked yes)
			(layer "B.SilkS")
			(effects
				(font
					(size 0.7874 0.5842)
					(thickness 0.1524)
				)
				(justify left mirror)
			)
		)
		(property "Value" ""
			(at 0 0 0)
			(layer "B.Fab")
			(effects
				(font
					(size 1.27 1.27)
				)
				(justify mirror)
			)
		)
		(duplicate_pad_numbers_are_jumpers no)
		(fp_line
			(start -0.7874 -0.4064)
			(end -0.7874 0.4064)
			(stroke
				(width 0.1524)
				(type default)
			)
			(layer "B.SilkS")
		)
		(fp_line
			(start -0.7874 0.4064)
			(end 0.7874 0.4064)
			(stroke
				(width 0.1524)
				(type default)
			)
			(layer "B.SilkS")
		)
		(fp_line
			(start 0.7874 -0.4064)
			(end -0.7874 -0.4064)
			(stroke
				(width 0.1524)
				(type default)
			)
			(layer "B.SilkS")
		)
		(fp_line
			(start 0.7874 0.4064)
			(end 0.7874 -0.4064)
			(stroke
				(width 0.1524)
				(type default)
			)
			(layer "B.SilkS")
		)
		(fp_poly
			(pts
				(xy 0.508 0.2794) (xy 0.508 0.2286) (xy 0.635 0.2286) (xy 0.635 -0.254) (xy 0.5334 -0.254) (xy 0.5334 -0.2794)
				(xy -0.5334 -0.2794) (xy -0.5334 -0.254) (xy -0.635 -0.254) (xy -0.635 0.254) (xy -0.5334 0.254)
				(xy -0.5334 0.2794)
			)
			(stroke
				(width 0)
				(type default)
			)
			(fill no)
			(layer "B.CrtYd")
		)
		(pad "1" smd rect
			(at -0.40005 0 180)
			(size 0.4572 0.508)
			(layers "B.Cu" "B.Mask" "B.Paste")
			(net "GND")
		)
		(pad "2" smd rect
			(at 0.40005 0 180)
			(size 0.4572 0.508)
			(layers "B.Cu" "B.Mask" "B.Paste")
			(net "PD_NODE1_DM2")
		)
	)
	(footprint ""
		(layer "B.Cu")
		(at 138.038078 -165.170358 180)
		(property "Reference" "R977"
			(at -3.46329 1.252982 0)
			(unlocked yes)
			(layer "B.SilkS")
			(effects
				(font
					(size 0.7874 0.5842)
					(thickness 0.1524)
				)
				(justify left mirror)
			)
		)
		(property "Value" ""
			(at 0 0 0)
			(layer "B.Fab")
			(effects
				(font
					(size 1.27 1.27)
				)
				(justify mirror)
			)
		)
		(duplicate_pad_numbers_are_jumpers no)
		(fp_line
			(start 0.7874 0.4064)
			(end 0.7874 -0.4064)
			(stroke
				(width 0.1524)
				(type default)
			)
			(layer "B.SilkS")
		)
		(fp_line
			(start 0.7874 -0.4064)
			(end -0.7874 -0.4064)
			(stroke
				(width 0.1524)
				(type default)
			)
			(layer "B.SilkS")
		)
		(fp_line
			(start -0.7874 0.4064)
			(end 0.7874 0.4064)
			(stroke
				(width 0.1524)
				(type default)
			)
			(layer "B.SilkS")
		)
		(fp_line
			(start -0.7874 -0.4064)
			(end -0.7874 0.4064)
			(stroke
				(width 0.1524)
				(type default)
			)
			(layer "B.SilkS")
		)
		(fp_poly
			(pts
				(xy 0.508 0.2794) (xy 0.508 0.2286) (xy 0.635 0.2286) (xy 0.635 -0.254) (xy 0.5334 -0.254) (xy 0.5334 -0.2794)
				(xy -0.5334 -0.2794) (xy -0.5334 -0.254) (xy -0.635 -0.254) (xy -0.635 0.254) (xy -0.5334 0.254)
				(xy -0.5334 0.2794)
			)
			(stroke
				(width 0)
				(type default)
			)
			(fill no)
			(layer "B.CrtYd")
		)
		(pad "1" smd rect
			(at -0.40005 0)
			(size 0.4572 0.508)
			(layers "B.Cu" "B.Mask" "B.Paste")
			(net "UART_T9_NODE4_TXD")
		)
		(pad "2" smd rect
			(at 0.40005 0)
			(size 0.4572 0.508)
			(layers "B.Cu" "B.Mask" "B.Paste")
			(net "UART_T9_NODE4_TXD_R")
		)
	)
)
